(kicad_pcb
	(version 20260206)
	(generator "pcbnew")
	(generator_version "10.0")
	(general
		(thickness 1.6)
		(legacy_teardrops no)
	)
	(paper "A4")
	(title_block
		(title "03242023_DA0F0TMBIJ0_F0T_Motherboard_J_brd_V01_OCP.brd")
		(comment 1 "Grand Teton / footprints 2013-2018 of 6105")
	)
	(layers
		(0 "F.Cu" signal "TOP")
		(4 "In1.Cu" signal "GND")
		(6 "In2.Cu" signal "IN1")
		(8 "In3.Cu" signal "GND1")
		(10 "In4.Cu" signal "IN2")
		(12 "In5.Cu" signal "GND2")
		(14 "In6.Cu" signal "IN3")
		(16 "In7.Cu" signal "GND3")
		(18 "In8.Cu" signal "VCC")
		(20 "In9.Cu" signal "VCC1")
		(22 "In10.Cu" signal "GND4")
		(24 "In11.Cu" signal "IN4")
		(26 "In12.Cu" signal "GND5")
		(28 "In13.Cu" signal "IN5")
		(30 "In14.Cu" signal "GND6")
		(32 "In15.Cu" signal "IN6")
		(34 "In16.Cu" signal "GND7")
		(2 "B.Cu" signal "BOTTOM")
		(9 "F.Adhes" user "F.Adhesive")
		(11 "B.Adhes" user "B.Adhesive")
		(13 "F.Paste" user "Package Geometry/Pastemask Top")
		(15 "B.Paste" user "Package Geometry/Pastemask Bottom")
		(5 "F.SilkS" user "Ref Des/Silkscreen Top")
		(7 "B.SilkS" user "Ref Des/Silkscreen Bottom")
		(1 "F.Mask" user "Board Geometry/Soldermask Top")
		(3 "B.Mask" user "Board Geometry/Soldermask Bottom")
		(17 "Dwgs.User" user "User.Drawings")
		(19 "Cmts.User" user "User.Comments")
		(21 "Eco1.User" user "User.Eco1")
		(23 "Eco2.User" user "User.Eco2")
		(25 "Edge.Cuts" user "Board Geometry/Outline")
		(27 "Margin" user)
		(31 "F.CrtYd" user "Package Geometry/Place Bound Top")
		(29 "B.CrtYd" user "Package Geometry/Place Bound Bottom")
		(35 "F.Fab" user "Ref Des/Assembly Top")
		(33 "B.Fab" user "Ref Des/Assembly Bottom")
	)
	(footprint ""
		(layer "F.Cu")
		(at 16.333724 -76.943204)
		(property "Reference" "C1876"
			(at 0 0 0)
			(layer "F.SilkS")
			(hide yes)
			(effects
				(font
					(size 1.27 1.27)
				)
			)
		)
		(property "Value" ""
			(at 0 0 0)
			(layer "F.Fab")
			(effects
				(font
					(size 1.27 1.27)
				)
			)
		)
		(duplicate_pad_numbers_are_jumpers no)
		(fp_line
			(start -0.7874 -0.4064)
			(end 0.7874 -0.4064)
			(stroke
				(width 0.1524)
				(type default)
			)
			(layer "F.SilkS")
		)
		(fp_line
			(start -0.7874 0.4064)
			(end -0.7874 -0.4064)
			(stroke
				(width 0.1524)
				(type default)
			)
			(layer "F.SilkS")
		)
		(fp_line
			(start 0.7874 -0.4064)
			(end 0.7874 0.4064)
			(stroke
				(width 0.1524)
				(type default)
			)
			(layer "F.SilkS")
		)
		(fp_line
			(start 0.7874 0.4064)
			(end -0.7874 0.4064)
			(stroke
				(width 0.1524)
				(type default)
			)
			(layer "F.SilkS")
		)
		(fp_line
			(start -0.67945 -0.305054)
			(end -0.12065 -0.305054)
			(stroke
				(width 0.1)
				(type default)
			)
			(layer "F.Fab")
		)
		(fp_line
			(start -0.67945 0.3048)
			(end -0.67945 -0.305054)
			(stroke
				(width 0.1)
				(type default)
			)
			(layer "F.Fab")
		)
		(fp_line
			(start -0.12065 -0.305054)
			(end -0.12065 -0.2794)
			(stroke
				(width 0.1)
				(type default)
			)
			(layer "F.Fab")
		)
		(fp_line
			(start -0.12065 -0.2794)
			(end 0.12065 -0.2794)
			(stroke
				(width 0.1)
				(type default)
			)
			(layer "F.Fab")
		)
		(fp_line
			(start -0.12065 0.2794)
			(end -0.12065 0.3048)
			(stroke
				(width 0.1)
				(type default)
			)
			(layer "F.Fab")
		)
		(fp_line
			(start -0.12065 0.3048)
			(end -0.67945 0.3048)
			(stroke
				(width 0.1)
				(type default)
			)
			(layer "F.Fab")
		)
		(fp_line
			(start 0.120396 0.2794)
			(end -0.12065 0.2794)
			(stroke
				(width 0.1)
				(type default)
			)
			(layer "F.Fab")
		)
		(fp_line
			(start 0.120396 0.3048)
			(end 0.120396 0.2794)
			(stroke
				(width 0.1)
				(type default)
			)
			(layer "F.Fab")
		)
		(fp_line
			(start 0.12065 -0.3048)
			(end 0.67945 -0.3048)
			(stroke
				(width 0.1)
				(type default)
			)
			(layer "F.Fab")
		)
		(fp_line
			(start 0.12065 -0.2794)
			(end 0.12065 -0.3048)
			(stroke
				(width 0.1)
				(type default)
			)
			(layer "F.Fab")
		)
		(fp_line
			(start 0.67945 -0.3048)
			(end 0.67945 0.3048)
			(stroke
				(width 0.1)
				(type default)
			)
			(layer "F.Fab")
		)
		(fp_line
			(start 0.67945 0.3048)
			(end 0.120396 0.3048)
			(stroke
				(width 0.1)
				(type default)
			)
			(layer "F.Fab")
		)
		(pad "1" smd circle
			(at -0.40005 0)
			(size 0 0)
			(layers "F.Cu" "F.Mask" "F.Paste")
			(net "P3V3_AUX")
		)
		(pad "2" smd circle
			(at 0.40005 0)
			(size 0 0)
			(layers "F.Cu" "F.Mask" "F.Paste")
			(net "GND")
		)
	)
	(footprint ""
		(layer "F.Cu")
		(at 65.861438 -22.235922 180)
		(property "Reference" "PR3850"
			(at 0 0 180)
			(layer "F.SilkS")
			(hide yes)
			(effects
				(font
					(size 1.27 1.27)
				)
			)
		)
		(property "Value" ""
			(at 0 0 180)
			(layer "F.Fab")
			(effects
				(font
					(size 1.27 1.27)
				)
			)
		)
		(duplicate_pad_numbers_are_jumpers no)
		(fp_line
			(start 0.7874 0.4064)
			(end -0.7874 0.4064)
			(stroke
				(width 0.1524)
				(type default)
			)
			(layer "F.SilkS")
		)
		(fp_line
			(start 0.7874 -0.4064)
			(end 0.7874 0.4064)
			(stroke
				(width 0.1524)
				(type default)
			)
			(layer "F.SilkS")
		)
		(fp_line
			(start -0.7874 0.4064)
			(end -0.7874 -0.4064)
			(stroke
				(width 0.1524)
				(type default)
			)
			(layer "F.SilkS")
		)
		(fp_line
			(start -0.7874 -0.4064)
			(end 0.7874 -0.4064)
			(stroke
				(width 0.1524)
				(type default)
			)
			(layer "F.SilkS")
		)
		(fp_line
			(start 0.67945 0.3048)
			(end 0.120396 0.3048)
			(stroke
				(width 0.1)
				(type default)
			)
			(layer "F.Fab")
		)
		(fp_line
			(start 0.67945 -0.3048)
			(end 0.67945 0.3048)
			(stroke
				(width 0.1)
				(type default)
			)
			(layer "F.Fab")
		)
		(fp_line
			(start 0.12065 -0.2794)
			(end 0.12065 -0.3048)
			(stroke
				(width 0.1)
				(type default)
			)
			(layer "F.Fab")
		)
		(fp_line
			(start 0.12065 -0.3048)
			(end 0.67945 -0.3048)
			(stroke
				(width 0.1)
				(type default)
			)
			(layer "F.Fab")
		)
		(fp_line
			(start 0.120396 0.3048)
			(end 0.120396 0.2794)
			(stroke
				(width 0.1)
				(type default)
			)
			(layer "F.Fab")
		)
		(fp_line
			(start 0.120396 0.2794)
			(end -0.12065 0.2794)
			(stroke
				(width 0.1)
				(type default)
			)
			(layer "F.Fab")
		)
		(fp_line
			(start -0.12065 0.3048)
			(end -0.67945 0.3048)
			(stroke
				(width 0.1)
				(type default)
			)
			(layer "F.Fab")
		)
		(fp_line
			(start -0.12065 0.2794)
			(end -0.12065 0.3048)
			(stroke
				(width 0.1)
				(type default)
			)
			(layer "F.Fab")
		)
		(fp_line
			(start -0.12065 -0.2794)
			(end 0.12065 -0.2794)
			(stroke
				(width 0.1)
				(type default)
			)
			(layer "F.Fab")
		)
		(fp_line
			(start -0.12065 -0.305054)
			(end -0.12065 -0.2794)
			(stroke
				(width 0.1)
				(type default)
			)
			(layer "F.Fab")
		)
		(fp_line
			(start -0.67945 0.3048)
			(end -0.67945 -0.305054)
			(stroke
				(width 0.1)
				(type default)
			)
			(layer "F.Fab")
		)
		(fp_line
			(start -0.67945 -0.305054)
			(end -0.12065 -0.305054)
			(stroke
				(width 0.1)
				(type default)
			)
			(layer "F.Fab")
		)
		(pad "1" smd circle
			(at -0.40005 0 180)
			(size 0 0)
			(layers "F.Cu" "F.Mask" "F.Paste")
			(net "P12V_OCP_V3_2")
		)
		(pad "2" smd circle
			(at 0.40005 0 180)
			(size 0 0)
			(layers "F.Cu" "F.Mask" "F.Paste")
			(net "P12V_OCP_AVIN_PD_2")
		)
	)
	(footprint ""
		(layer "F.Cu")
		(at 287.494726 -367.919508)
		(property "Reference" "PR1297"
			(at 0 0 0)
			(layer "F.SilkS")
			(hide yes)
			(effects
				(font
					(size 1.27 1.27)
				)
			)
		)
		(property "Value" ""
			(at 0 0 0)
			(layer "F.Fab")
			(effects
				(font
					(size 1.27 1.27)
				)
			)
		)
		(duplicate_pad_numbers_are_jumpers no)
		(fp_line
			(start -0.7874 -0.4064)
			(end 0.7874 -0.4064)
			(stroke
				(width 0.1524)
				(type default)
			)
			(layer "F.SilkS")
		)
		(fp_line
			(start -0.7874 0.4064)
			(end -0.7874 -0.4064)
			(stroke
				(width 0.1524)
				(type default)
			)
			(layer "F.SilkS")
		)
		(fp_line
			(start 0.7874 -0.4064)
			(end 0.7874 0.4064)
			(stroke
				(width 0.1524)
				(type default)
			)
			(layer "F.SilkS")
		)
		(fp_line
			(start 0.7874 0.4064)
			(end -0.7874 0.4064)
			(stroke
				(width 0.1524)
				(type default)
			)
			(layer "F.SilkS")
		)
		(fp_line
			(start -0.67945 -0.305054)
			(end -0.12065 -0.305054)
			(stroke
				(width 0.1)
				(type default)
			)
			(layer "F.Fab")
		)
		(fp_line
			(start -0.67945 0.3048)
			(end -0.67945 -0.305054)
			(stroke
				(width 0.1)
				(type default)
			)
			(layer "F.Fab")
		)
		(fp_line
			(start -0.12065 -0.305054)
			(end -0.12065 -0.2794)
			(stroke
				(width 0.1)
				(type default)
			)
			(layer "F.Fab")
		)
		(fp_line
			(start -0.12065 -0.2794)
			(end 0.12065 -0.2794)
			(stroke
				(width 0.1)
				(type default)
			)
			(layer "F.Fab")
		)
		(fp_line
			(start -0.12065 0.2794)
			(end -0.12065 0.3048)
			(stroke
				(width 0.1)
				(type default)
			)
			(layer "F.Fab")
		)
		(fp_line
			(start -0.12065 0.3048)
			(end -0.67945 0.3048)
			(stroke
				(width 0.1)
				(type default)
			)
			(layer "F.Fab")
		)
		(fp_line
			(start 0.120396 0.2794)
			(end -0.12065 0.2794)
			(stroke
				(width 0.1)
				(type default)
			)
			(layer "F.Fab")
		)
		(fp_line
			(start 0.120396 0.3048)
			(end 0.120396 0.2794)
			(stroke
				(width 0.1)
				(type default)
			)
			(layer "F.Fab")
		)
		(fp_line
			(start 0.12065 -0.3048)
			(end 0.67945 -0.3048)
			(stroke
				(width 0.1)
				(type default)
			)
			(layer "F.Fab")
		)
		(fp_line
			(start 0.12065 -0.2794)
			(end 0.12065 -0.3048)
			(stroke
				(width 0.1)
				(type default)
			)
			(layer "F.Fab")
		)
		(fp_line
			(start 0.67945 -0.3048)
			(end 0.67945 0.3048)
			(stroke
				(width 0.1)
				(type default)
			)
			(layer "F.Fab")
		)
		(fp_line
			(start 0.67945 0.3048)
			(end 0.120396 0.3048)
			(stroke
				(width 0.1)
				(type default)
			)
			(layer "F.Fab")
		)
		(pad "1" smd circle
			(at -0.40005 0)
			(size 0 0)
			(layers "F.Cu" "F.Mask" "F.Paste")
			(net "PVCCFA_EHV_FIVRA_CPU0_LSET4")
		)
		(pad "2" smd circle
			(at 0.40005 0)
			(size 0 0)
			(layers "F.Cu" "F.Mask" "F.Paste")
			(net "GND")
		)
	)
	(footprint ""
		(layer "F.Cu")
		(at 68.212462 -38.405562 180)
		(property "Reference" "R3620"
			(at 0 0 180)
			(layer "F.SilkS")
			(hide yes)
			(effects
				(font
					(size 1.27 1.27)
				)
			)
		)
		(property "Value" ""
			(at 0 0 180)
			(layer "F.Fab")
			(effects
				(font
					(size 1.27 1.27)
				)
			)
		)
		(duplicate_pad_numbers_are_jumpers no)
		(fp_line
			(start 0.7874 0.4064)
			(end -0.7874 0.4064)
			(stroke
				(width 0.1524)
				(type default)
			)
			(layer "F.SilkS")
		)
		(fp_line
			(start 0.7874 -0.4064)
			(end 0.7874 0.4064)
			(stroke
				(width 0.1524)
				(type default)
			)
			(layer "F.SilkS")
		)
		(fp_line
			(start -0.7874 0.4064)
			(end -0.7874 -0.4064)
			(stroke
				(width 0.1524)
				(type default)
			)
			(layer "F.SilkS")
		)
		(fp_line
			(start -0.7874 -0.4064)
			(end 0.7874 -0.4064)
			(stroke
				(width 0.1524)
				(type default)
			)
			(layer "F.SilkS")
		)
		(fp_line
			(start 0.67945 0.3048)
			(end 0.120396 0.3048)
			(stroke
				(width 0.1)
				(type default)
			)
			(layer "F.Fab")
		)
		(fp_line
			(start 0.67945 -0.3048)
			(end 0.67945 0.3048)
			(stroke
				(width 0.1)
				(type default)
			)
			(layer "F.Fab")
		)
		(fp_line
			(start 0.12065 -0.2794)
			(end 0.12065 -0.3048)
			(stroke
				(width 0.1)
				(type default)
			)
			(layer "F.Fab")
		)
		(fp_line
			(start 0.12065 -0.3048)
			(end 0.67945 -0.3048)
			(stroke
				(width 0.1)
				(type default)
			)
			(layer "F.Fab")
		)
		(fp_line
			(start 0.120396 0.3048)
			(end 0.120396 0.2794)
			(stroke
				(width 0.1)
				(type default)
			)
			(layer "F.Fab")
		)
		(fp_line
			(start 0.120396 0.2794)
			(end -0.12065 0.2794)
			(stroke
				(width 0.1)
				(type default)
			)
			(layer "F.Fab")
		)
		(fp_line
			(start -0.12065 0.3048)
			(end -0.67945 0.3048)
			(stroke
				(width 0.1)
				(type default)
			)
			(layer "F.Fab")
		)
		(fp_line
			(start -0.12065 0.2794)
			(end -0.12065 0.3048)
			(stroke
				(width 0.1)
				(type default)
			)
			(layer "F.Fab")
		)
		(fp_line
			(start -0.12065 -0.2794)
			(end 0.12065 -0.2794)
			(stroke
				(width 0.1)
				(type default)
			)
			(layer "F.Fab")
		)
		(fp_line
			(start -0.12065 -0.305054)
			(end -0.12065 -0.2794)
			(stroke
				(width 0.1)
				(type default)
			)
			(layer "F.Fab")
		)
		(fp_line
			(start -0.67945 0.3048)
			(end -0.67945 -0.305054)
			(stroke
				(width 0.1)
				(type default)
			)
			(layer "F.Fab")
		)
		(fp_line
			(start -0.67945 -0.305054)
			(end -0.12065 -0.305054)
			(stroke
				(width 0.1)
				(type default)
			)
			(layer "F.Fab")
		)
		(pad "1" smd circle
			(at -0.40005 0 180)
			(size 0 0)
			(layers "F.Cu" "F.Mask" "F.Paste")
			(net "INA230_3_A0")
		)
		(pad "2" smd circle
			(at 0.40005 0 180)
			(size 0 0)
			(layers "F.Cu" "F.Mask" "F.Paste")
			(net "SMB_INA230_3_3V3AUX_SCL_R1")
		)
	)
	(footprint ""
		(layer "F.Cu")
		(at 49.610264 -363.228636 90)
		(property "Reference" "PC417"
			(at 0 0 90)
			(layer "F.SilkS")
			(hide yes)
			(effects
				(font
					(size 1.27 1.27)
				)
			)
		)
		(property "Value" ""
			(at 0 0 90)
			(layer "F.Fab")
			(effects
				(font
					(size 1.27 1.27)
				)
			)
		)
		(duplicate_pad_numbers_are_jumpers no)
		(fp_line
			(start -3.400044 1.249934)
			(end 3.400044 1.249934)
			(stroke
				(width 0.1524)
				(type default)
			)
			(layer "F.SilkS")
		)
		(fp_circle
			(center 0 1.249934)
			(end 0 4.649978)
			(stroke
				(width 0.1524)
				(type default)
			)
			(fill no)
			(layer "F.SilkS")
		)
		(fp_poly
			(pts
				(arc
					(start -3.400044 1.249934)
					(mid 0 4.649978)
					(end 3.400044 1.249934)
				)
			)
			(stroke
				(width 0)
				(type default)
			)
			(fill yes)
			(layer "F.SilkS")
		)
		(fp_circle
			(center 0 1.249934)
			(end 0 4.649978)
			(stroke
				(width 0.1)
				(type default)
			)
			(fill no)
			(layer "F.Fab")
		)
		(pad "1" thru_hole rect
			(at 0 0 90)
			(size 1.524 1.524)
			(drill 1.016)
			(layers "*.Cu" "*.Mask")
			(remove_unused_layers no)
			(net "SW_P12V_PVCCFA_EHV_FIVRA_CPU1_L")
			(clearance 0)
			(padstack
				(mode front_inner_back)
				(layer "Inner"
					(shape circle)
					(size 1.524 1.524)
					(clearance 0)
				)
				(layer "B.Cu"
					(shape rect)
					(size 1.524 1.524)
					(clearance 0)
				)
			)
		)
		(pad "2" thru_hole circle
			(at 0 2.500122 90)
			(size 1.524 1.524)
			(drill 1.016)
			(layers "*.Cu" "*.Mask")
			(remove_unused_layers no)
			(net "GND")
			(clearance 0)
		)
	)
	(footprint ""
		(layer "F.Cu")
		(at 180.528468 -53.980334 180)
		(property "Reference" "C1104"
			(at 0 0 180)
			(layer "F.SilkS")
			(hide yes)
			(effects
				(font
					(size 1.27 1.27)
				)
			)
		)
		(property "Value" ""
			(at 0 0 180)
			(layer "F.Fab")
			(effects
				(font
					(size 1.27 1.27)
				)
			)
		)
		(duplicate_pad_numbers_are_jumpers no)
		(fp_line
			(start 0.299974 0.150114)
			(end -0.299974 0.150114)
			(stroke
				(width 0.1)
				(type default)
			)
			(layer "F.Fab")
		)
		(fp_line
			(start 0.299974 -0.150114)
			(end 0.299974 0.150114)
			(stroke
				(width 0.1)
				(type default)
			)
			(layer "F.Fab")
		)
		(fp_line
			(start -0.299974 0.150114)
			(end -0.299974 -0.150114)
			(stroke
				(width 0.1)
				(type default)
			)
			(layer "F.Fab")
		)
		(fp_line
			(start -0.299974 -0.150114)
			(end 0.299974 -0.150114)
			(stroke
				(width 0.1)
				(type default)
			)
			(layer "F.Fab")
		)
		(pad "1" smd rect
			(at -0.2667 0 180)
			(size 0.3048 0.381)
			(layers "F.Cu" "F.Mask" "F.Paste")
			(net "P3E_PCH_M2_TX_DP<0>")
		)
		(pad "2" smd rect
			(at 0.2667 0 180)
			(size 0.3048 0.381)
			(layers "F.Cu" "F.Mask" "F.Paste")
			(net "P3E_PCH_M2_TX_C_DP<0>")
		)
		(zone
			(layer "In1.Cu")
			(hatch none 0.5)
			(connect_pads
				(clearance 0)
			)
			(min_thickness 0.25)
			(keepout
				(tracks not_allowed)
				(vias allowed)
				(pads allowed)
				(copperpour not_allowed)
				(footprints allowed)
			)
			(placement
				(enabled no)
				(sheetname "")
			)
			(fill
				(thermal_gap 0.5)
				(thermal_bridge_width 0.5)
				(island_removal_mode 0)
			)
			(polygon
				(pts
					(arc
						(start 180.388768 -54.221634)
						(mid 180.44265 -54.199316)
						(end 180.464968 -54.145434)
					)
					(arc
						(start 180.464968 -53.815234)
						(mid 180.44265 -53.761352)
						(end 180.388768 -53.739034)
					)
					(arc
						(start 180.134768 -53.739034)
						(mid 180.080886 -53.761352)
						(end 180.058568 -53.815234)
					)
					(arc
						(start 180.058568 -54.145434)
						(mid 180.080886 -54.199316)
						(end 180.134768 -54.221634)
					)
				)
			)
		)
		(zone
			(layer "In1.Cu")
			(hatch none 0.5)
			(connect_pads
				(clearance 0)
			)
			(min_thickness 0.25)
			(keepout
				(tracks not_allowed)
				(vias allowed)
				(pads allowed)
				(copperpour not_allowed)
				(footprints allowed)
			)
			(placement
				(enabled no)
				(sheetname "")
			)
			(fill
				(thermal_gap 0.5)
				(thermal_bridge_width 0.5)
				(island_removal_mode 0)
			)
			(polygon
				(pts
					(arc
						(start 180.922168 -54.221634)
						(mid 180.97605 -54.199316)
						(end 180.998368 -54.145434)
					)
					(arc
						(start 180.998368 -53.815234)
						(mid 180.97605 -53.761352)
						(end 180.922168 -53.739034)
					)
					(arc
						(start 180.668168 -53.739034)
						(mid 180.614286 -53.761352)
						(end 180.591968 -53.815234)
					)
					(arc
						(start 180.591968 -54.145434)
						(mid 180.614286 -54.199316)
						(end 180.668168 -54.221634)
					)
				)
			)
		)
	)
)
